# BASEBOARD_FAB2 (Tioga Pass) — schematic netlist excerpt (pin names and nets, part order shuffled) for the footprints in the layout excerpt that follows; sources: Cadence DE-HDL packaged netlist, KiCad conversion of Wiwynn_Tioga_Pass_MB.brd

J2W2  SKT-SATA7P-6P-165-GP-U1  pkg SOCKET-G6  page 172
  H1  = GND
  H2  = GND
  NP1  = NC
  NP2  = NC
  P1  = P5V_HDD_SATA
  P2  = P5V_HDD_SATA
  P3  = GND
  P4  = GND
  P5  = P12V_HDD_SATA
  P6  = P12V_HDD_SATA
  S1  = GND
  S2  = SATA6G_S1_TX_C_DP
  S3  = SATA6G_S1_TX_C_DN
  S4  = GND
  S5  = SATA6G_S1_RX_C_DN
  S6  = SATA6G_S1_RX_C_DP
  S7  = GND

(kicad_pcb
	(version 20260206)
	(generator "pcbnew")
	(generator_version "10.0")
	(general
		(thickness 1.6)
		(legacy_teardrops no)
	)
	(paper "A4")
	(title_block
		(title "Wiwynn_Tioga_Pass_MB.brd")
		(comment 1 "Tioga Pass / footprint 2126 of 4770 (J2W2), pads 1-17 of 17")
	)
	(layers
		(0 "F.Cu" signal "TOP")
		(4 "In1.Cu" signal "L2GND")
		(6 "In2.Cu" signal "L3")
		(8 "In3.Cu" signal "L4GND")
		(10 "In4.Cu" signal "L5")
		(12 "In5.Cu" signal "L6GND")
		(14 "In6.Cu" signal "L7VCC")
		(16 "In7.Cu" signal "L8VCC")
		(18 "In8.Cu" signal "L9GND")
		(20 "In9.Cu" signal "L10")
		(22 "In10.Cu" signal "L11GND")
		(24 "In11.Cu" signal "L12")
		(26 "In12.Cu" signal "L13GND")
		(2 "B.Cu" signal "BOTTOM")
		(9 "F.Adhes" user "F.Adhesive")
		(11 "B.Adhes" user "B.Adhesive")
		(13 "F.Paste" user "Package Geometry/Pastemask Top")
		(15 "B.Paste" user "Package Geometry/Pastemask Bottom")
		(5 "F.SilkS" user "Ref Des/Silkscreen Top")
		(7 "B.SilkS" user "Ref Des/Silkscreen Bottom")
		(1 "F.Mask" user "Board Geometry/Soldermask Top")
		(3 "B.Mask" user "Board Geometry/Soldermask Bottom")
		(17 "Dwgs.User" user "User.Drawings")
		(19 "Cmts.User" user "User.Comments")
		(21 "Eco1.User" user "User.Eco1")
		(23 "Eco2.User" user "User.Eco2")
		(25 "Edge.Cuts" user "Board Geometry/Outline")
		(27 "Margin" user)
		(31 "F.CrtYd" user "Package Geometry/Place Bound Top")
		(29 "B.CrtYd" user "Package Geometry/Place Bound Bottom")
		(35 "F.Fab" user "Ref Des/Assembly Top")
		(33 "B.Fab" user "Ref Des/Assembly Bottom")
	)
	(footprint ""
		(layer "F.Cu")
		(at 437.930036 -135.64489 180)
		(property "Reference" "J2W2"
			(at 0 0 180)
			(layer "F.SilkS")
			(hide yes)
			(effects
				(font
					(size 1.27 1.27)
				)
			)
		)
		(property "Value" "*"
			(at -2.3622 -8.3185 180)
			(unlocked yes)
			(layer "F.Fab")
			(hide yes)
			(effects
				(font
					(size 1.27 1.016)
					(thickness 0.1524)
				)
			)
		)
		(property "Device Type" "SKT-SATA7P-6P-165-GP-U1_SOCKETA"
			(at -2.3622 -9.8425 180)
			(unlocked yes)
			(layer "F.Fab")
			(hide yes)
			(effects
				(font
					(size 1.27 1.016)
					(thickness 0.1524)
				)
			)
		)
		(duplicate_pad_numbers_are_jumpers no)
		(pad "" np_thru_hole circle
			(at -12.500102 -1.400048 180)
			(size 0.254 0.254)
			(drill 1.651)
			(layers "*.Cu" "*.Mask")
			(clearance 1.0541)
			(thermal_gap 1.0541)
		)
		(pad "" np_thru_hole circle
			(at 12.500102 -1.400048 180)
			(size 0.254 0.254)
			(drill 1.651)
			(layers "*.Cu" "*.Mask")
			(clearance 1.0541)
			(thermal_gap 1.0541)
		)
		(pad "H1" smd rect
			(at 16.249904 0 180)
			(size 2.5908 3.683)
			(layers "F.Cu" "F.Mask" "F.Paste")
			(net "GND")
		)
		(pad "H2" smd rect
			(at -16.249904 0 180)
			(size 2.5908 3.683)
			(layers "F.Cu" "F.Mask" "F.Paste")
			(net "GND")
		)
		(pad "P1" thru_hole oval
			(at -4.45008 0.700024 180)
			(size 0.8128 0.9144)
			(drill 0.5588)
			(layers "*.Cu" "*.Mask")
			(remove_unused_layers no)
			(net "P5V_HDD_SATA")
			(clearance 0.2286)
			(thermal_gap 0.2286)
		)
		(pad "P2" thru_hole oval
			(at -5.450078 0.700024 180)
			(size 0.8128 0.9144)
			(drill 0.5588)
			(layers "*.Cu" "*.Mask")
			(remove_unused_layers no)
			(net "P5V_HDD_SATA")
			(clearance 0.2286)
			(thermal_gap 0.2286)
		)
		(pad "P3" thru_hole oval
			(at -6.450076 0.700024 180)
			(size 0.8128 0.9144)
			(drill 0.5588)
			(layers "*.Cu" "*.Mask")
			(remove_unused_layers no)
			(net "GND")
			(clearance 0.2286)
			(thermal_gap 0.2286)
		)
		(pad "P4" thru_hole oval
			(at -7.450074 0.700024 180)
			(size 0.8128 0.9144)
			(drill 0.5588)
			(layers "*.Cu" "*.Mask")
			(remove_unused_layers no)
			(net "GND")
			(clearance 0.2286)
			(thermal_gap 0.2286)
		)
		(pad "P5" thru_hole oval
			(at -8.450072 0.700024 180)
			(size 0.8128 0.9144)
			(drill 0.5588)
			(layers "*.Cu" "*.Mask")
			(remove_unused_layers no)
			(net "P12V_HDD_SATA")
			(clearance 0.2286)
			(thermal_gap 0.2286)
		)
		(pad "P6" thru_hole oval
			(at -9.45007 0.700024 180)
			(size 0.8128 0.9144)
			(drill 0.5588)
			(layers "*.Cu" "*.Mask")
			(remove_unused_layers no)
			(net "P12V_HDD_SATA")
			(clearance 0.2286)
			(thermal_gap 0.2286)
		)
		(pad "S1" thru_hole circle
			(at 9.379966 0.700024 180)
			(size 1.016 1.016)
			(drill 0.6604)
			(layers "*.Cu" "*.Mask")
			(remove_unused_layers no)
			(net "GND")
			(clearance 0.1778)
			(thermal_gap 0.1778)
		)
		(pad "S2" thru_hole circle
			(at 8.109966 0.700024 180)
			(size 1.016 1.016)
			(drill 0.6604)
			(layers "*.Cu" "*.Mask")
			(remove_unused_layers no)
			(net "SATA6G_S1_TX_C_DP")
			(clearance 0.1778)
			(thermal_gap 0.1778)
		)
		(pad "S3" thru_hole circle
			(at 6.839966 0.700024 180)
			(size 1.016 1.016)
			(drill 0.6604)
			(layers "*.Cu" "*.Mask")
			(remove_unused_layers no)
			(net "SATA6G_S1_TX_C_DN")
			(clearance 0.1778)
			(thermal_gap 0.1778)
		)
		(pad "S4" thru_hole circle
			(at 5.569966 0.700024 180)
			(size 1.016 1.016)
			(drill 0.6604)
			(layers "*.Cu" "*.Mask")
			(remove_unused_layers no)
			(net "GND")
			(clearance 0.1778)
			(thermal_gap 0.1778)
		)
		(pad "S5" thru_hole circle
			(at 4.299966 0.700024 180)
			(size 1.016 1.016)
			(drill 0.6604)
			(layers "*.Cu" "*.Mask")
			(remove_unused_layers no)
			(net "SATA6G_S1_RX_C_DN")
			(clearance 0.1778)
			(thermal_gap 0.1778)
		)
		(pad "S6" thru_hole circle
			(at 3.029966 0.700024 180)
			(size 1.016 1.016)
			(drill 0.6604)
			(layers "*.Cu" "*.Mask")
			(remove_unused_layers no)
			(net "SATA6G_S1_RX_C_DP")
			(clearance 0.1778)
			(thermal_gap 0.1778)
		)
		(pad "S7" thru_hole circle
			(at 1.759966 0.700024 180)
			(size 1.016 1.016)
			(drill 0.6604)
			(layers "*.Cu" "*.Mask")
			(remove_unused_layers no)
			(net "GND")
			(clearance 0.1778)
			(thermal_gap 0.1778)
		)
	)
)
